(kicad_pcb
	(version 20260206)
	(generator "pcbnew")
	(generator_version "10.0")
	(general
		(thickness 1.6)
		(legacy_teardrops no)
	)
	(paper "A4")
	(title_block
		(title "timecard-production-celestica-r4006 — R4006-B0001-02_R01.brd")
		(comment 1 "Time Appliance Project (Time Card) / footprints 191-196 of 1113")
	)
	(layers
		(0 "F.Cu" signal "TOP")
		(4 "In1.Cu" signal "L02_GND1")
		(6 "In2.Cu" signal "L03_SIG1")
		(8 "In3.Cu" signal "L04_GND2")
		(10 "In4.Cu" signal "L05_VCC1")
		(12 "In5.Cu" signal "L06_VCC2")
		(14 "In6.Cu" signal "L07_GND3")
		(16 "In7.Cu" signal "L08_SIG2")
		(18 "In8.Cu" signal "L09_GND4")
		(2 "B.Cu" signal "BOTTOM")
		(9 "F.Adhes" user "F.Adhesive")
		(11 "B.Adhes" user "B.Adhesive")
		(13 "F.Paste" user "Package Geometry/Pastemask Top")
		(15 "B.Paste" user "Package Geometry/Pastemask Bottom")
		(5 "F.SilkS" user "Ref Des/Silkscreen Top")
		(7 "B.SilkS" user "Ref Des/Silkscreen Bottom")
		(1 "F.Mask" user "Board Geometry/Soldermask Top")
		(3 "B.Mask" user "Board Geometry/Soldermask Bottom")
		(17 "Dwgs.User" user "User.Drawings")
		(19 "Cmts.User" user "User.Comments")
		(21 "Eco1.User" user "User.Eco1")
		(23 "Eco2.User" user "User.Eco2")
		(25 "Edge.Cuts" user "Board Geometry/Outline")
		(27 "Margin" user)
		(31 "F.CrtYd" user "Package Geometry/Place Bound Top")
		(29 "B.CrtYd" user "Package Geometry/Place Bound Bottom")
		(35 "F.Fab" user "Ref Des/Assembly Top")
		(33 "B.Fab" user "Ref Des/Assembly Bottom")
	)
	(footprint ""
		(layer "F.Cu")
		(at 136.906 -41.402 -90)
		(property "Reference" "C271"
			(at 3.302 -0.03937 90)
			(unlocked yes)
			(layer "F.SilkS")
			(effects
				(font
					(size 0.7874 0.5842)
					(thickness 0.1524)
				)
			)
		)
		(property "Value" "VAL*"
			(at 0.0762 3.134106 270)
			(unlocked yes)
			(layer "F.Fab")
			(hide yes)
			(effects
				(font
					(size 0.7874 0.5842)
					(thickness 0.1524)
				)
			)
		)
		(property "Device Type" "CAPACITOR-G107-0F476-AM,47UF,2A"
			(at 0.0508 2.194306 270)
			(unlocked yes)
			(layer "F.Fab")
			(hide yes)
			(effects
				(font
					(size 0.7874 0.5842)
					(thickness 0.1524)
				)
			)
		)
		(property "User Part Number" "PARTNUM*"
			(at 0.1016 5.013706 270)
			(unlocked yes)
			(layer "Cmts.User")
			(hide yes)
			(effects
				(font
					(size 0.7874 0.5842)
					(thickness 0.1524)
				)
			)
		)
		(property "Tolerance" "TOL*"
			(at 0.0762 4.048506 270)
			(unlocked yes)
			(layer "Cmts.User")
			(hide yes)
			(effects
				(font
					(size 0.7874 0.5842)
					(thickness 0.1524)
				)
			)
		)
		(duplicate_pad_numbers_are_jumpers no)
		(fp_line
			(start -1.5748 0.9398)
			(end 1.5748 0.9398)
			(stroke
				(width 0.1)
				(type default)
			)
			(layer "F.SilkS")
		)
		(fp_line
			(start 1.5748 0.9398)
			(end 1.5748 -0.9398)
			(stroke
				(width 0.1)
				(type default)
			)
			(layer "F.SilkS")
		)
		(fp_line
			(start -1.5748 -0.9398)
			(end -1.5748 0.9398)
			(stroke
				(width 0.1)
				(type default)
			)
			(layer "F.SilkS")
		)
		(fp_line
			(start 1.5748 -0.9398)
			(end -1.5748 -0.9398)
			(stroke
				(width 0.1)
				(type default)
			)
			(layer "F.SilkS")
		)
		(fp_rect
			(start -1.5748 0.9398)
			(end 1.5748 -0.9398)
			(stroke
				(width 0)
				(type default)
			)
			(fill no)
			(layer "F.CrtYd")
		)
		(fp_line
			(start -1.016 0.635)
			(end 1.016 0.635)
			(stroke
				(width 0.1)
				(type default)
			)
			(layer "F.Fab")
		)
		(fp_line
			(start 1.016 0.635)
			(end 1.016 -0.635)
			(stroke
				(width 0.1)
				(type default)
			)
			(layer "F.Fab")
		)
		(fp_line
			(start -1.016 -0.635)
			(end -1.016 0.635)
			(stroke
				(width 0.1)
				(type default)
			)
			(layer "F.Fab")
		)
		(fp_line
			(start 1.016 -0.635)
			(end -1.016 -0.635)
			(stroke
				(width 0.1)
				(type default)
			)
			(layer "F.Fab")
		)
		(pad "1" smd rect
			(at -0.8382 0 270)
			(size 0.9652 1.3716)
			(layers "F.Cu" "F.Mask" "F.Paste")
			(net "XP1R0V_FPGA")
		)
		(pad "2" smd rect
			(at 0.8382 0 270)
			(size 0.9652 1.3716)
			(layers "F.Cu" "F.Mask" "F.Paste")
			(net "SG")
		)
		(zone
			(layer "F.Cu")
			(hatch none 0.5)
			(connect_pads
				(clearance 0)
			)
			(min_thickness 0.25)
			(keepout
				(tracks allowed)
				(vias not_allowed)
				(pads allowed)
				(copperpour not_allowed)
				(footprints allowed)
			)
			(placement
				(enabled no)
				(sheetname "")
			)
			(fill
				(thermal_gap 0.5)
				(thermal_bridge_width 0.5)
				(island_removal_mode 0)
			)
			(polygon
				(pts
					(xy 136.271 -41.6306) (xy 136.271 -41.1734) (xy 137.541 -41.1734) (xy 137.541 -41.6306)
				)
			)
		)
	)
	(footprint ""
		(layer "F.Cu")
		(at 12.7 -39.878 180)
		(property "Reference" "C310"
			(at -1.016 -1.04775 0)
			(unlocked yes)
			(layer "F.SilkS")
			(effects
				(font
					(size 0.635 0.4064)
					(thickness 0.1524)
				)
			)
		)
		(property "Value" "VAL*"
			(at 0.193548 2.13614 180)
			(unlocked yes)
			(layer "F.Fab")
			(hide yes)
			(effects
				(font
					(size 0.7874 0.5842)
					(thickness 0.1524)
				)
			)
		)
		(property "User Part Number" "PARTNUM*"
			(at 0.216154 4.185666 180)
			(unlocked yes)
			(layer "Cmts.User")
			(hide yes)
			(effects
				(font
					(size 0.7874 0.5842)
					(thickness 0.1524)
				)
			)
		)
		(property "Device Type" "CAPACITOR-G104-0A180-FJ,18PF,5%"
			(at 0.184404 1.180592 180)
			(unlocked yes)
			(layer "F.Fab")
			(hide yes)
			(effects
				(font
					(size 0.7874 0.5842)
					(thickness 0.1524)
				)
			)
		)
		(property "Tolerance" "TOL*"
			(at 0.216154 3.1496 180)
			(unlocked yes)
			(layer "Cmts.User")
			(hide yes)
			(effects
				(font
					(size 0.7874 0.5842)
					(thickness 0.1524)
				)
			)
		)
		(duplicate_pad_numbers_are_jumpers no)
		(fp_line
			(start 0.671322 0.4445)
			(end -0.671322 0.4445)
			(stroke
				(width 0.1)
				(type default)
			)
			(layer "F.SilkS")
		)
		(fp_line
			(start 0.671322 -0.4445)
			(end 0.671322 0.4445)
			(stroke
				(width 0.1)
				(type default)
			)
			(layer "F.SilkS")
		)
		(fp_line
			(start -0.671322 0.4445)
			(end -0.671322 -0.4445)
			(stroke
				(width 0.1)
				(type default)
			)
			(layer "F.SilkS")
		)
		(fp_line
			(start -0.671322 -0.4445)
			(end 0.671322 -0.4445)
			(stroke
				(width 0.1)
				(type default)
			)
			(layer "F.SilkS")
		)
		(fp_rect
			(start -0.671322 0.4445)
			(end 0.671322 -0.4445)
			(stroke
				(width 0)
				(type default)
			)
			(fill no)
			(layer "F.CrtYd")
		)
		(fp_line
			(start 0.31496 0.1651)
			(end 0.31496 -0.1651)
			(stroke
				(width 0.1)
				(type default)
			)
			(layer "F.Fab")
		)
		(fp_line
			(start 0.31496 -0.1651)
			(end -0.31496 -0.1651)
			(stroke
				(width 0.1)
				(type default)
			)
			(layer "F.Fab")
		)
		(fp_line
			(start -0.31496 0.1651)
			(end 0.31496 0.1651)
			(stroke
				(width 0.1)
				(type default)
			)
			(layer "F.Fab")
		)
		(fp_line
			(start -0.31496 -0.1651)
			(end -0.31496 0.1651)
			(stroke
				(width 0.1)
				(type default)
			)
			(layer "F.Fab")
		)
		(pad "1" smd rect
			(at -0.264922 0 180)
			(size 0.3048 0.381)
			(layers "F.Cu" "F.Mask" "F.Paste")
			(net "SG")
		)
		(pad "2" smd rect
			(at 0.264922 0 180)
			(size 0.3048 0.381)
			(layers "F.Cu" "F.Mask" "F.Paste")
			(net "UNNAMED_12_CAPACITOR_I318_2")
		)
		(zone
			(layer "F.Cu")
			(hatch none 0.5)
			(connect_pads
				(clearance 0)
			)
			(min_thickness 0.25)
			(keepout
				(tracks not_allowed)
				(vias allowed)
				(pads allowed)
				(copperpour not_allowed)
				(footprints allowed)
			)
			(placement
				(enabled no)
				(sheetname "")
			)
			(fill
				(thermal_gap 0.5)
				(thermal_bridge_width 0.5)
				(island_removal_mode 0)
			)
			(polygon
				(pts
					(xy 12.812522 -40.0685) (xy 12.587478 -40.0685) (xy 12.587478 -39.6875) (xy 12.812522 -39.6875)
				)
			)
		)
		(zone
			(layer "F.Cu")
			(hatch none 0.5)
			(connect_pads
				(clearance 0)
			)
			(min_thickness 0.25)
			(keepout
				(tracks allowed)
				(vias not_allowed)
				(pads allowed)
				(copperpour not_allowed)
				(footprints allowed)
			)
			(placement
				(enabled no)
				(sheetname "")
			)
			(fill
				(thermal_gap 0.5)
				(thermal_bridge_width 0.5)
				(island_removal_mode 0)
			)
			(polygon
				(pts
					(xy 12.812522 -39.6875) (xy 12.812522 -40.0685) (xy 12.587478 -40.0685) (xy 12.587478 -39.6875)
				)
			)
		)
	)
	(footprint ""
		(layer "F.Cu")
		(at 4.073906 -61.60008)
		(property "Reference" "J3"
			(at 4.943094 -2.24155 0)
			(unlocked yes)
			(layer "F.SilkS")
			(effects
				(font
					(size 0.7874 0.5842)
					(thickness 0.1524)
				)
			)
		)
		(property "Value" ""
			(at 0 0 0)
			(layer "F.Fab")
			(effects
				(font
					(size 1.27 1.27)
				)
			)
		)
		(property "Device Type" "CONN_JACK_1P_GH4_S_TH-G200-130A"
			(at -5.098288 5.899912 0)
			(unlocked yes)
			(layer "F.Fab")
			(hide yes)
			(effects
				(font
					(size 0.7874 0.5842)
					(thickness 0.1524)
				)
			)
		)
		(property "User Part Number" "PARTNUM*"
			(at -5.098288 7.093712 0)
			(unlocked yes)
			(layer "Cmts.User")
			(hide yes)
			(effects
				(font
					(size 0.7874 0.5842)
					(thickness 0.1524)
				)
			)
		)
		(duplicate_pad_numbers_are_jumpers no)
		(fp_line
			(start -13.953998 -3.937)
			(end 3.937 -3.937)
			(stroke
				(width 0.1)
				(type default)
			)
			(layer "F.SilkS")
		)
		(fp_line
			(start -13.953998 3.937)
			(end -13.953998 -3.937)
			(stroke
				(width 0.1)
				(type default)
			)
			(layer "F.SilkS")
		)
		(fp_line
			(start 3.937 -3.937)
			(end 3.937 3.937)
			(stroke
				(width 0.1)
				(type default)
			)
			(layer "F.SilkS")
		)
		(fp_line
			(start 3.937 3.937)
			(end -13.953998 3.937)
			(stroke
				(width 0.1)
				(type default)
			)
			(layer "F.SilkS")
		)
		(fp_rect
			(start -8.763 8.763)
			(end 8.763 -8.763)
			(stroke
				(width 0)
				(type default)
			)
			(fill no)
			(layer "B.CrtYd")
		)
		(fp_rect
			(start -14.207998 4.191)
			(end 4.191 -4.191)
			(stroke
				(width 0)
				(type default)
			)
			(fill no)
			(layer "F.CrtYd")
		)
		(fp_line
			(start -13.699998 -3.599942)
			(end 3.599942 -3.599942)
			(stroke
				(width 0.1)
				(type default)
			)
			(layer "F.Fab")
		)
		(fp_line
			(start -13.699998 3.599942)
			(end -13.699998 -3.599942)
			(stroke
				(width 0.1)
				(type default)
			)
			(layer "F.Fab")
		)
		(fp_line
			(start 3.599942 -3.599942)
			(end 3.599942 3.599942)
			(stroke
				(width 0.1)
				(type default)
			)
			(layer "F.Fab")
		)
		(fp_line
			(start 3.599942 3.599942)
			(end -13.699998 3.599942)
			(stroke
				(width 0.1)
				(type default)
			)
			(layer "F.Fab")
		)
		(fp_text user "GH1"
			(at 0.117094 -4.28117 0)
			(unlocked yes)
			(layer "F.SilkS")
			(effects
				(font
					(size 0.635 0.4064)
					(thickness 0.1524)
				)
			)
		)
		(fp_text user "GH3"
			(at 0.752094 4.68503 0)
			(unlocked yes)
			(layer "F.SilkS")
			(effects
				(font
					(size 0.635 0.4064)
					(thickness 0.1524)
				)
			)
		)
		(fp_text user "GH2"
			(at 2.530094 -4.28117 0)
			(unlocked yes)
			(layer "F.SilkS")
			(effects
				(font
					(size 0.635 0.4064)
					(thickness 0.1524)
				)
			)
		)
		(fp_text user "GH4"
			(at 3.038094 4.68503 0)
			(unlocked yes)
			(layer "F.SilkS")
			(effects
				(font
					(size 0.635 0.4064)
					(thickness 0.1524)
				)
			)
		)
		(fp_text user "1"
			(at 4.191 -0.35433 0)
			(unlocked yes)
			(layer "F.SilkS")
			(effects
				(font
					(size 0.7874 0.5842)
					(thickness 0.1524)
				)
				(justify left)
			)
		)
		(fp_text user "GH1"
			(at -2.549906 -4.14655 0)
			(unlocked yes)
			(layer "F.Fab")
			(effects
				(font
					(size 0.7874 0.5842)
					(thickness 0.1524)
				)
			)
		)
		(fp_text user "GH3"
			(at -2.422906 4.229608 0)
			(unlocked yes)
			(layer "F.Fab")
			(effects
				(font
					(size 0.7874 0.5842)
					(thickness 0.1524)
				)
			)
		)
		(fp_text user "GH4"
			(at 2.403094 4.229608 0)
			(unlocked yes)
			(layer "F.Fab")
			(effects
				(font
					(size 0.7874 0.5842)
					(thickness 0.1524)
				)
			)
		)
		(fp_text user "GH2"
			(at 2.54 -4.57073 0)
			(unlocked yes)
			(layer "F.Fab")
			(effects
				(font
					(size 0.7874 0.5842)
					(thickness 0.1524)
				)
			)
		)
		(fp_text user "1"
			(at 4.191 -0.35433 0)
			(unlocked yes)
			(layer "F.Fab")
			(effects
				(font
					(size 0.7874 0.5842)
					(thickness 0.1524)
				)
				(justify left)
			)
		)
		(pad "1" thru_hole circle
			(at 0 0)
			(size 2.1844 2.1844)
			(drill 1.4986)
			(layers "*.Cu" "*.Mask")
			(remove_unused_layers no)
			(net "SMA1_SIG_IO_CONN")
			(padstack
				(mode front_inner_back)
				(layer "Inner"
					(shape circle)
					(size 2.1844 2.1844)
					(clearance -0.0508)
				)
				(layer "B.Cu"
					(shape circle)
					(size 2.1844 2.1844)
				)
			)
		)
		(pad "GH1" thru_hole circle
			(at -2.54 -2.54)
			(size 2.286 2.286)
			(drill 1.6002)
			(layers "*.Cu" "*.Mask")
			(remove_unused_layers no)
			(net "SG")
			(padstack
				(mode front_inner_back)
				(layer "Inner"
					(shape circle)
					(size 2.286 2.286)
					(clearance -0.0508)
				)
				(layer "B.Cu"
					(shape circle)
					(size 2.286 2.286)
				)
			)
		)
		(pad "GH2" thru_hole circle
			(at 2.54 -2.54)
			(size 2.286 2.286)
			(drill 1.6002)
			(layers "*.Cu" "*.Mask")
			(remove_unused_layers no)
			(net "SG")
			(padstack
				(mode front_inner_back)
				(layer "Inner"
					(shape circle)
					(size 2.286 2.286)
					(clearance -0.0508)
				)
				(layer "B.Cu"
					(shape circle)
					(size 2.286 2.286)
				)
			)
		)
		(pad "GH3" thru_hole circle
			(at -2.54 2.54)
			(size 2.286 2.286)
			(drill 1.6002)
			(layers "*.Cu" "*.Mask")
			(remove_unused_layers no)
			(net "SG")
			(padstack
				(mode front_inner_back)
				(layer "Inner"
					(shape circle)
					(size 2.286 2.286)
					(clearance -0.0508)
				)
				(layer "B.Cu"
					(shape circle)
					(size 2.286 2.286)
				)
			)
		)
		(pad "GH4" thru_hole circle
			(at 2.54 2.54)
			(size 2.286 2.286)
			(drill 1.6002)
			(layers "*.Cu" "*.Mask")
			(remove_unused_layers no)
			(net "SG")
			(padstack
				(mode front_inner_back)
				(layer "Inner"
					(shape circle)
					(size 2.286 2.286)
					(clearance -0.0508)
				)
				(layer "B.Cu"
					(shape circle)
					(size 2.286 2.286)
				)
			)
		)
	)
	(footprint ""
		(layer "F.Cu")
		(at 5.0038 -68.201032 90)
		(property "Reference" "R391"
			(at 3.553968 -0.51943 90)
			(unlocked yes)
			(layer "F.SilkS")
			(effects
				(font
					(size 0.7874 0.5842)
					(thickness 0.1524)
				)
			)
		)
		(property "Value" "VAL*"
			(at 0.02032 2.13233 90)
			(unlocked yes)
			(layer "F.Fab")
			(hide yes)
			(effects
				(font
					(size 0.7874 0.5842)
					(thickness 0.1524)
				)
			)
		)
		(property "Tolerance" "TOL*"
			(at 0.044704 3.05435 90)
			(unlocked yes)
			(layer "Cmts.User")
			(hide yes)
			(effects
				(font
					(size 0.7874 0.5842)
					(thickness 0.1524)
				)
			)
		)
		(property "User Part Number" "PARTNUM*"
			(at 0.02032 4.024884 90)
			(unlocked yes)
			(layer "Cmts.User")
			(hide yes)
			(effects
				(font
					(size 0.7874 0.5842)
					(thickness 0.1524)
				)
			)
		)
		(property "Device Type" "RESISTOR-G155-133R0-01,33OHM,1%"
			(at 0.008382 1.210564 90)
			(unlocked yes)
			(layer "F.Fab")
			(hide yes)
			(effects
				(font
					(size 0.7874 0.5842)
					(thickness 0.1524)
				)
			)
		)
		(duplicate_pad_numbers_are_jumpers no)
		(fp_line
			(start 1.143 -0.5588)
			(end -1.143 -0.5588)
			(stroke
				(width 0.1)
				(type default)
			)
			(layer "F.SilkS")
		)
		(fp_line
			(start -1.143 -0.5588)
			(end -1.143 0.5588)
			(stroke
				(width 0.1)
				(type default)
			)
			(layer "F.SilkS")
		)
		(fp_line
			(start 1.143 0.5588)
			(end 1.143 -0.5588)
			(stroke
				(width 0.1)
				(type default)
			)
			(layer "F.SilkS")
		)
		(fp_line
			(start -1.143 0.5588)
			(end 1.143 0.5588)
			(stroke
				(width 0.1)
				(type default)
			)
			(layer "F.SilkS")
		)
		(fp_rect
			(start -1.143 -0.5588)
			(end 1.143 0.5588)
			(stroke
				(width 0)
				(type default)
			)
			(fill no)
			(layer "F.CrtYd")
		)
		(fp_line
			(start 0.508 -0.3048)
			(end -0.508 -0.3048)
			(stroke
				(width 0.1)
				(type default)
			)
			(layer "F.Fab")
		)
		(fp_line
			(start -0.508 -0.3048)
			(end -0.508 0.3048)
			(stroke
				(width 0.1)
				(type default)
			)
			(layer "F.Fab")
		)
		(fp_line
			(start 0.508 0.3048)
			(end 0.508 -0.3048)
			(stroke
				(width 0.1)
				(type default)
			)
			(layer "F.Fab")
		)
		(fp_line
			(start -0.508 0.3048)
			(end 0.508 0.3048)
			(stroke
				(width 0.1)
				(type default)
			)
			(layer "F.Fab")
		)
		(pad "1" smd rect
			(at -0.5334 0 90)
			(size 0.7112 0.6096)
			(layers "F.Cu" "F.Mask" "F.Paste")
			(net "SMA3_LED_BLUE_N")
		)
		(pad "2" smd rect
			(at 0.5334 0 90)
			(size 0.7112 0.6096)
			(layers "F.Cu" "F.Mask" "F.Paste")
			(net "UNNAMED_14_LED4PV14_I267_1")
		)
		(zone
			(layer "F.Cu")
			(hatch none 0.5)
			(connect_pads
				(clearance 0)
			)
			(min_thickness 0.25)
			(keepout
				(tracks not_allowed)
				(vias allowed)
				(pads allowed)
				(copperpour not_allowed)
				(footprints allowed)
			)
			(placement
				(enabled no)
				(sheetname "")
			)
			(fill
				(thermal_gap 0.5)
				(thermal_bridge_width 0.5)
				(island_removal_mode 0)
			)
			(polygon
				(pts
					(xy 4.699 -68.124832) (xy 5.3086 -68.124832) (xy 5.3086 -68.277232) (xy 4.699 -68.277232)
				)
			)
		)
		(zone
			(layer "F.Cu")
			(hatch none 0.5)
			(connect_pads
				(clearance 0)
			)
			(min_thickness 0.25)
			(keepout
				(tracks allowed)
				(vias not_allowed)
				(pads allowed)
				(copperpour not_allowed)
				(footprints allowed)
			)
			(placement
				(enabled no)
				(sheetname "")
			)
			(fill
				(thermal_gap 0.5)
				(thermal_bridge_width 0.5)
				(island_removal_mode 0)
			)
			(polygon
				(pts
					(xy 4.699 -68.124832) (xy 5.3086 -68.124832) (xy 5.3086 -68.277232) (xy 4.699 -68.277232)
				)
			)
		)
	)
	(footprint ""
		(layer "F.Cu")
		(at 50.419 -131.953)
		(property "Reference" "SP72"
			(at 0 0 0)
			(layer "F.SilkS")
			(hide yes)
			(effects
				(font
					(size 1.27 1.27)
				)
			)
		)
		(property "Value" ""
			(at 0 0 0)
			(layer "F.Fab")
			(effects
				(font
					(size 1.27 1.27)
				)
			)
		)
		(duplicate_pad_numbers_are_jumpers no)
	)
	(footprint ""
		(layer "F.Cu")
		(at 19.177 -15.748)
		(property "Reference" "TP20"
			(at 0.9398 0.86995 0)
			(unlocked yes)
			(layer "F.SilkS")
			(effects
				(font
					(size 0.635 0.4064)
					(thickness 0.1524)
				)
				(justify left)
			)
		)
		(property "Value" ""
			(at 0 0 0)
			(layer "F.Fab")
			(effects
				(font
					(size 1.27 1.27)
				)
			)
		)
		(property "Device Type" "TP_PIONT-TP010CT020B030_PTH-TPA"
			(at -1.341882 0.996696 0)
			(unlocked yes)
			(layer "F.Fab")
			(hide yes)
			(effects
				(font
					(size 0.7874 0.5842)
					(thickness 0.000001)
				)
				(justify left)
			)
		)
		(duplicate_pad_numbers_are_jumpers no)
		(fp_poly
			(pts
				(arc
					(start 0.889 0)
					(mid -0.889 0)
					(end 0.889 0)
				)
			)
			(stroke
				(width 0)
				(type default)
			)
			(fill no)
			(layer "B.CrtYd")
		)
		(fp_poly
			(pts
				(arc
					(start 0.889 0)
					(mid -0.889 0)
					(end 0.889 0)
				)
			)
			(stroke
				(width 0)
				(type default)
			)
			(fill no)
			(layer "F.CrtYd")
		)
		(pad "1" thru_hole circle
			(at 0 0)
			(size 0.508 0.508)
			(drill 0.254)
			(layers "*.Cu" "*.Mask")
			(remove_unused_layers no)
			(net "SEC_EEPROM_WP")
			(clearance 0.1016)
			(padstack
				(mode front_inner_back)
				(layer "Inner"
					(shape circle)
					(size 0.508 0.508)
					(clearance 0.1016)
				)
				(layer "B.Cu"
					(shape circle)
					(size 0.762 0.762)
					(clearance -0.0254)
				)
			)
		)
	)
)
